FILE_TYPE = MACRO_DRAWING;
SET COLOR_WIRE YELLOW;
SET COLOR_PROP ORANGE;
SET COLOR_DOT WHITE;
SET COLOR_ARC YELLOW;
SET COLOR_BODY GREEN;
SET COLOR_NOTE PURPLE;
SET PROP_DISPLAY VALUE;
SET PAGE_NUMBER P74;
FORCEADD Q_CAP..1
(-8550 3000);
FORCEPROP 1 LAST LOCATION C2661
J 0
(-8500 3100);
DISPLAY 0.489362 (-8500 3100);
PAINT SKYBLUE (-8500 3100);
FORCEPROP 2 LAST $SEC 1
J 0
(-8500 3200);
DISPLAY 0.680851 (-8500 3200);
PAINT MONO (-8500 3200);
DISPLAY INVISIBLE (-8500 3200);
FORCEPROP 2 LAST CDS_SEC 1
J 0
(-8500 3200);
DISPLAY 1.021277 (-8500 3200);
DISPLAY INVISIBLE (-8500 3200);
FORCEPROP 1 LASTPIN (-8550 3100) $PN 1
J 0
(-8540 3080);
DISPLAY 0.489362 (-8540 3080);
FORCEPROP 1 LASTPIN (-8550 2900) $PN 2
J 0
(-8540 2880);
DISPLAY 0.489362 (-8540 2880);
FORCEPROP 1 LAST MATERIAL X6S
J 0
(-8500 2900);
DISPLAY 0.489362 (-8500 2900);
PAINT SKYBLUE (-8500 2900);
FORCEPROP 1 LAST TOLERANCE 20%
J 0
(-8500 2950);
DISPLAY 0.489362 (-8500 2950);
PAINT SKYBLUE (-8500 2950);
FORCEPROP 1 LAST VALUE 22UF
J 0
(-8500 3050);
DISPLAY 0.489362 (-8500 3050);
PAINT SKYBLUE (-8500 3050);
FORCEPROP 1 LAST PART_NUMBER CH622KMEB02
J 0
(-8500 2850);
DISPLAY 0.489362 (-8500 2850);
PAINT SKYBLUE (-8500 2850);
FORCEPROP 1 LAST VOLTAGE 4V
J 0
(-8500 3000);
DISPLAY 0.489362 (-8500 3000);
PAINT SKYBLUE (-8500 3000);
FORCEPROP 1 LAST PACK_TYPE C0402
J 0
(-8500 2800);
DISPLAY 0.489362 (-8500 2800);
PAINT SKYBLUE (-8500 2800);
FORCEPROP 2 LAST CDS_LIB pure_quanta
J 0
(-8550 3000);
PAINT MONO (-8550 3000);
DISPLAY INVISIBLE (-8550 3000);
FORCEPROP 1 LAST PATH I1
J 0
(-8500 3150);
DISPLAY 0.978723 (-8500 3150);
PAINT WHITE (-8500 3150);
DISPLAY INVISIBLE (-8500 3150);
FORCEADD Q_CAP..1
(-7650 3775);
FORCEPROP 1 LAST LOCATION C2665
J 0
(-7600 3875);
DISPLAY 0.489362 (-7600 3875);
PAINT SKYBLUE (-7600 3875);
FORCEPROP 2 LAST $SEC 1
J 0
(-7600 3975);
DISPLAY 0.680851 (-7600 3975);
PAINT MONO (-7600 3975);
DISPLAY INVISIBLE (-7600 3975);
FORCEPROP 2 LAST CDS_SEC 1
J 0
(-7600 3975);
DISPLAY 1.021277 (-7600 3975);
DISPLAY INVISIBLE (-7600 3975);
FORCEPROP 1 LASTPIN (-7650 3875) $PN 1
J 0
(-7640 3855);
DISPLAY 0.489362 (-7640 3855);
FORCEPROP 1 LASTPIN (-7650 3675) $PN 2
J 0
(-7640 3655);
DISPLAY 0.489362 (-7640 3655);
FORCEPROP 1 LAST MATERIAL X6S
J 0
(-7600 3675);
DISPLAY 0.489362 (-7600 3675);
PAINT SKYBLUE (-7600 3675);
FORCEPROP 1 LAST TOLERANCE 20%
J 0
(-7600 3725);
DISPLAY 0.489362 (-7600 3725);
PAINT SKYBLUE (-7600 3725);
FORCEPROP 1 LAST VALUE 22UF
J 0
(-7600 3825);
DISPLAY 0.489362 (-7600 3825);
PAINT SKYBLUE (-7600 3825);
FORCEPROP 1 LAST PART_NUMBER CH622KMEB02
J 0
(-7600 3625);
DISPLAY 0.489362 (-7600 3625);
PAINT SKYBLUE (-7600 3625);
FORCEPROP 1 LAST VOLTAGE 4V
J 0
(-7600 3775);
DISPLAY 0.489362 (-7600 3775);
PAINT SKYBLUE (-7600 3775);
FORCEPROP 1 LAST PACK_TYPE C0402
J 0
(-7600 3575);
DISPLAY 0.489362 (-7600 3575);
PAINT SKYBLUE (-7600 3575);
FORCEPROP 2 LAST CDS_LIB pure_quanta
J 0
(-7650 3775);
PAINT MONO (-7650 3775);
DISPLAY INVISIBLE (-7650 3775);
FORCEPROP 1 LAST PATH I10
J 0
(-7600 3925);
DISPLAY 0.978723 (-7600 3925);
PAINT WHITE (-7600 3925);
DISPLAY INVISIBLE (-7600 3925);
FORCEADD Q_CAP..1
(-7200 3775);
FORCEPROP 1 LAST LOCATION C2667
J 0
(-7150 3875);
DISPLAY 0.489362 (-7150 3875);
PAINT SKYBLUE (-7150 3875);
FORCEPROP 2 LAST $SEC 1
J 0
(-7150 3975);
DISPLAY 0.680851 (-7150 3975);
PAINT MONO (-7150 3975);
DISPLAY INVISIBLE (-7150 3975);
FORCEPROP 2 LAST CDS_SEC 1
J 0
(-7150 3975);
DISPLAY 1.021277 (-7150 3975);
DISPLAY INVISIBLE (-7150 3975);
FORCEPROP 1 LASTPIN (-7200 3875) $PN 1
J 0
(-7190 3855);
DISPLAY 0.489362 (-7190 3855);
FORCEPROP 1 LASTPIN (-7200 3675) $PN 2
J 0
(-7190 3655);
DISPLAY 0.489362 (-7190 3655);
FORCEPROP 1 LAST MATERIAL X6S
J 0
(-7150 3675);
DISPLAY 0.489362 (-7150 3675);
PAINT SKYBLUE (-7150 3675);
FORCEPROP 1 LAST TOLERANCE 20%
J 0
(-7150 3725);
DISPLAY 0.489362 (-7150 3725);
PAINT SKYBLUE (-7150 3725);
FORCEPROP 1 LAST VALUE 22UF
J 0
(-7150 3825);
DISPLAY 0.489362 (-7150 3825);
PAINT SKYBLUE (-7150 3825);
FORCEPROP 1 LAST PART_NUMBER CH622KMEB02
J 0
(-7150 3625);
DISPLAY 0.489362 (-7150 3625);
PAINT SKYBLUE (-7150 3625);
FORCEPROP 1 LAST VOLTAGE 4V
J 0
(-7150 3775);
DISPLAY 0.489362 (-7150 3775);
PAINT SKYBLUE (-7150 3775);
FORCEPROP 1 LAST PACK_TYPE C0402
J 0
(-7150 3575);
DISPLAY 0.489362 (-7150 3575);
PAINT SKYBLUE (-7150 3575);
FORCEPROP 2 LAST CDS_LIB pure_quanta
J 0
(-7200 3775);
PAINT MONO (-7200 3775);
DISPLAY INVISIBLE (-7200 3775);
FORCEPROP 1 LAST PATH I11
J 0
(-7150 3925);
DISPLAY 0.978723 (-7150 3925);
PAINT WHITE (-7150 3925);
DISPLAY INVISIBLE (-7150 3925);
FORCEADD Q_CAP..1
(-6750 3775);
FORCEPROP 1 LAST LOCATION C2668
J 0
(-6700 3875);
DISPLAY 0.489362 (-6700 3875);
PAINT SKYBLUE (-6700 3875);
FORCEPROP 2 LAST $SEC 1
J 0
(-6700 3975);
DISPLAY 0.680851 (-6700 3975);
PAINT MONO (-6700 3975);
DISPLAY INVISIBLE (-6700 3975);
FORCEPROP 2 LAST CDS_SEC 1
J 0
(-6700 3975);
DISPLAY 1.021277 (-6700 3975);
DISPLAY INVISIBLE (-6700 3975);
FORCEPROP 1 LASTPIN (-6750 3875) $PN 1
J 0
(-6740 3855);
DISPLAY 0.489362 (-6740 3855);
FORCEPROP 1 LASTPIN (-6750 3675) $PN 2
J 0
(-6740 3655);
DISPLAY 0.489362 (-6740 3655);
FORCEPROP 1 LAST MATERIAL X6S
J 0
(-6700 3675);
DISPLAY 0.489362 (-6700 3675);
PAINT SKYBLUE (-6700 3675);
FORCEPROP 1 LAST TOLERANCE 20%
J 0
(-6700 3725);
DISPLAY 0.489362 (-6700 3725);
PAINT SKYBLUE (-6700 3725);
FORCEPROP 1 LAST VALUE 22UF
J 0
(-6700 3825);
DISPLAY 0.489362 (-6700 3825);
PAINT SKYBLUE (-6700 3825);
FORCEPROP 1 LAST PART_NUMBER CH622KMEB02
J 0
(-6700 3625);
DISPLAY 0.489362 (-6700 3625);
PAINT SKYBLUE (-6700 3625);
FORCEPROP 1 LAST VOLTAGE 4V
J 0
(-6700 3775);
DISPLAY 0.489362 (-6700 3775);
PAINT SKYBLUE (-6700 3775);
FORCEPROP 1 LAST PACK_TYPE C0402
J 0
(-6700 3575);
DISPLAY 0.489362 (-6700 3575);
PAINT SKYBLUE (-6700 3575);
FORCEPROP 2 LAST CDS_LIB pure_quanta
J 0
(-6750 3775);
PAINT MONO (-6750 3775);
DISPLAY INVISIBLE (-6750 3775);
FORCEPROP 1 LAST PATH I12
J 0
(-6700 3925);
DISPLAY 0.978723 (-6700 3925);
PAINT WHITE (-6700 3925);
DISPLAY INVISIBLE (-6700 3925);
FORCEADD Q_CAP..1
(-6300 3775);
FORCEPROP 1 LAST LOCATION C2669
J 0
(-6250 3875);
DISPLAY 0.489362 (-6250 3875);
PAINT SKYBLUE (-6250 3875);
FORCEPROP 2 LAST $SEC 1
J 0
(-6250 3975);
DISPLAY 0.680851 (-6250 3975);
PAINT MONO (-6250 3975);
DISPLAY INVISIBLE (-6250 3975);
FORCEPROP 2 LAST CDS_SEC 1
J 0
(-6250 3975);
DISPLAY 1.021277 (-6250 3975);
DISPLAY INVISIBLE (-6250 3975);
FORCEPROP 1 LASTPIN (-6300 3875) $PN 1
J 0
(-6290 3855);
DISPLAY 0.489362 (-6290 3855);
FORCEPROP 1 LASTPIN (-6300 3675) $PN 2
J 0
(-6290 3655);
DISPLAY 0.489362 (-6290 3655);
FORCEPROP 1 LAST MATERIAL X6S
J 0
(-6250 3675);
DISPLAY 0.489362 (-6250 3675);
PAINT SKYBLUE (-6250 3675);
FORCEPROP 1 LAST TOLERANCE 20%
J 0
(-6250 3725);
DISPLAY 0.489362 (-6250 3725);
PAINT SKYBLUE (-6250 3725);
FORCEPROP 1 LAST VALUE 22UF
J 0
(-6250 3825);
DISPLAY 0.489362 (-6250 3825);
PAINT SKYBLUE (-6250 3825);
FORCEPROP 1 LAST PART_NUMBER CH622KMEB02
J 0
(-6250 3625);
DISPLAY 0.489362 (-6250 3625);
PAINT SKYBLUE (-6250 3625);
FORCEPROP 1 LAST VOLTAGE 4V
J 0
(-6250 3775);
DISPLAY 0.489362 (-6250 3775);
PAINT SKYBLUE (-6250 3775);
FORCEPROP 1 LAST PACK_TYPE C0402
J 0
(-6250 3575);
DISPLAY 0.489362 (-6250 3575);
PAINT SKYBLUE (-6250 3575);
FORCEPROP 2 LAST CDS_LIB pure_quanta
J 0
(-6300 3775);
PAINT MONO (-6300 3775);
DISPLAY INVISIBLE (-6300 3775);
FORCEPROP 1 LAST PATH I13
J 0
(-6250 3925);
DISPLAY 0.978723 (-6250 3925);
PAINT WHITE (-6250 3925);
DISPLAY INVISIBLE (-6250 3925);
FORCEADD Q_CAP..1
(-5850 3775);
FORCEPROP 1 LAST LOCATION C2670
J 0
(-5800 3875);
DISPLAY 0.489362 (-5800 3875);
PAINT SKYBLUE (-5800 3875);
FORCEPROP 2 LAST $SEC 1
J 0
(-5800 3975);
DISPLAY 0.680851 (-5800 3975);
PAINT MONO (-5800 3975);
DISPLAY INVISIBLE (-5800 3975);
FORCEPROP 2 LAST CDS_SEC 1
J 0
(-5800 3975);
DISPLAY 1.021277 (-5800 3975);
DISPLAY INVISIBLE (-5800 3975);
FORCEPROP 1 LASTPIN (-5850 3875) $PN 1
J 0
(-5840 3855);
DISPLAY 0.489362 (-5840 3855);
FORCEPROP 1 LASTPIN (-5850 3675) $PN 2
J 0
(-5840 3655);
DISPLAY 0.489362 (-5840 3655);
FORCEPROP 1 LAST MATERIAL X6S
J 0
(-5800 3675);
DISPLAY 0.489362 (-5800 3675);
PAINT SKYBLUE (-5800 3675);
FORCEPROP 1 LAST TOLERANCE 20%
J 0
(-5800 3725);
DISPLAY 0.489362 (-5800 3725);
PAINT SKYBLUE (-5800 3725);
FORCEPROP 1 LAST VALUE 22UF
J 0
(-5800 3825);
DISPLAY 0.489362 (-5800 3825);
PAINT SKYBLUE (-5800 3825);
FORCEPROP 1 LAST PART_NUMBER CH622KMEB02
J 0
(-5800 3625);
DISPLAY 0.489362 (-5800 3625);
PAINT SKYBLUE (-5800 3625);
FORCEPROP 1 LAST VOLTAGE 4V
J 0
(-5800 3775);
DISPLAY 0.489362 (-5800 3775);
PAINT SKYBLUE (-5800 3775);
FORCEPROP 1 LAST PACK_TYPE C0402
J 0
(-5800 3575);
DISPLAY 0.489362 (-5800 3575);
PAINT SKYBLUE (-5800 3575);
FORCEPROP 2 LAST CDS_LIB pure_quanta
J 0
(-5850 3775);
PAINT MONO (-5850 3775);
DISPLAY INVISIBLE (-5850 3775);
FORCEPROP 1 LAST PATH I14
J 0
(-5800 3925);
DISPLAY 0.978723 (-5800 3925);
PAINT WHITE (-5800 3925);
DISPLAY INVISIBLE (-5800 3925);
FORCEADD Q_CAP..1
(-5400 3775);
FORCEPROP 1 LAST LOCATION C2671
J 0
(-5350 3875);
DISPLAY 0.489362 (-5350 3875);
PAINT SKYBLUE (-5350 3875);
FORCEPROP 2 LAST $SEC 1
J 0
(-5350 3975);
DISPLAY 0.680851 (-5350 3975);
PAINT MONO (-5350 3975);
DISPLAY INVISIBLE (-5350 3975);
FORCEPROP 2 LAST CDS_SEC 1
J 0
(-5350 3975);
DISPLAY 1.021277 (-5350 3975);
DISPLAY INVISIBLE (-5350 3975);
FORCEPROP 1 LASTPIN (-5400 3875) $PN 1
J 0
(-5390 3855);
DISPLAY 0.489362 (-5390 3855);
FORCEPROP 1 LASTPIN (-5400 3675) $PN 2
J 0
(-5390 3655);
DISPLAY 0.489362 (-5390 3655);
FORCEPROP 1 LAST MATERIAL X6S
J 0
(-5350 3675);
DISPLAY 0.489362 (-5350 3675);
PAINT SKYBLUE (-5350 3675);
FORCEPROP 1 LAST TOLERANCE 20%
J 0
(-5350 3725);
DISPLAY 0.489362 (-5350 3725);
PAINT SKYBLUE (-5350 3725);
FORCEPROP 1 LAST VALUE 22UF
J 0
(-5350 3825);
DISPLAY 0.489362 (-5350 3825);
PAINT SKYBLUE (-5350 3825);
FORCEPROP 1 LAST PART_NUMBER CH622KMEB02
J 0
(-5350 3625);
DISPLAY 0.489362 (-5350 3625);
PAINT SKYBLUE (-5350 3625);
FORCEPROP 1 LAST VOLTAGE 4V
J 0
(-5350 3775);
DISPLAY 0.489362 (-5350 3775);
PAINT SKYBLUE (-5350 3775);
FORCEPROP 1 LAST PACK_TYPE C0402
J 0
(-5350 3575);
DISPLAY 0.489362 (-5350 3575);
PAINT SKYBLUE (-5350 3575);
FORCEPROP 2 LAST CDS_LIB pure_quanta
J 0
(-5400 3775);
PAINT MONO (-5400 3775);
DISPLAY INVISIBLE (-5400 3775);
FORCEPROP 1 LAST PATH I15
J 0
(-5350 3925);
DISPLAY 0.978723 (-5350 3925);
PAINT WHITE (-5350 3925);
DISPLAY INVISIBLE (-5350 3925);
FORCEADD Q_CAP..1
(-4950 3775);
FORCEPROP 1 LAST LOCATION C2672
J 0
(-4900 3875);
DISPLAY 0.489362 (-4900 3875);
PAINT SKYBLUE (-4900 3875);
FORCEPROP 2 LAST $SEC 1
J 0
(-4900 3975);
DISPLAY 0.680851 (-4900 3975);
PAINT MONO (-4900 3975);
DISPLAY INVISIBLE (-4900 3975);
FORCEPROP 2 LAST CDS_SEC 1
J 0
(-4900 3975);
DISPLAY 1.021277 (-4900 3975);
DISPLAY INVISIBLE (-4900 3975);
FORCEPROP 1 LASTPIN (-4950 3875) $PN 1
J 0
(-4940 3855);
DISPLAY 0.489362 (-4940 3855);
FORCEPROP 1 LASTPIN (-4950 3675) $PN 2
J 0
(-4940 3655);
DISPLAY 0.489362 (-4940 3655);
FORCEPROP 1 LAST MATERIAL X6S
J 0
(-4900 3675);
DISPLAY 0.489362 (-4900 3675);
PAINT SKYBLUE (-4900 3675);
FORCEPROP 1 LAST TOLERANCE 20%
J 0
(-4900 3725);
DISPLAY 0.489362 (-4900 3725);
PAINT SKYBLUE (-4900 3725);
FORCEPROP 1 LAST VALUE 22UF
J 0
(-4900 3825);
DISPLAY 0.489362 (-4900 3825);
PAINT SKYBLUE (-4900 3825);
FORCEPROP 1 LAST PART_NUMBER CH622KMEB02
J 0
(-4900 3625);
DISPLAY 0.489362 (-4900 3625);
PAINT SKYBLUE (-4900 3625);
FORCEPROP 1 LAST VOLTAGE 4V
J 0
(-4900 3775);
DISPLAY 0.489362 (-4900 3775);
PAINT SKYBLUE (-4900 3775);
FORCEPROP 1 LAST PACK_TYPE C0402
J 0
(-4900 3575);
DISPLAY 0.489362 (-4900 3575);
PAINT SKYBLUE (-4900 3575);
FORCEPROP 2 LAST CDS_LIB pure_quanta
J 0
(-4950 3775);
PAINT MONO (-4950 3775);
DISPLAY INVISIBLE (-4950 3775);
FORCEPROP 1 LAST PATH I16
J 0
(-4900 3925);
DISPLAY 0.978723 (-4900 3925);
PAINT WHITE (-4900 3925);
DISPLAY INVISIBLE (-4900 3925);
FORCEADD UNIVERSAL_GND..1
(-4550 3400);
FORCEPROP 3 LASTPIN (-4550 3450) SIG_NAME GND\g
J 0
(-4540 3460);
DISPLAY 0.659574 (-4540 3460);
PAINT MONO (-4540 3460);
DISPLAY INVISIBLE (-4540 3460);
FORCEPROP 2 LAST CDS_LIB pure_quanta_power
J 0
(-4550 3400);
PAINT MONO (-4550 3400);
DISPLAY INVISIBLE (-4550 3400);
FORCEPROP 1 LAST PATH I17
J 0
(-4475 3400);
DISPLAY 0.872340 (-4475 3400);
PAINT AQUA (-4475 3400);
DISPLAY INVISIBLE (-4475 3400);
FORCEPROP 1 LAST HDL_POWER GND
J 1
(-4525 3325);
DISPLAY 0.872340 (-4525 3325);
PAINT GREEN (-4525 3325);
DISPLAY INVISIBLE (-4525 3325);
FORCEADD Q_CAP..1
(-4550 3775);
FORCEPROP 1 LAST LOCATION C2673
J 0
(-4500 3875);
DISPLAY 0.489362 (-4500 3875);
PAINT SKYBLUE (-4500 3875);
FORCEPROP 2 LAST $SEC 1
J 0
(-4500 3975);
DISPLAY 0.680851 (-4500 3975);
PAINT MONO (-4500 3975);
DISPLAY INVISIBLE (-4500 3975);
FORCEPROP 2 LAST CDS_SEC 1
J 0
(-4500 3975);
DISPLAY 1.021277 (-4500 3975);
DISPLAY INVISIBLE (-4500 3975);
FORCEPROP 1 LASTPIN (-4550 3875) $PN 1
J 0
(-4540 3855);
DISPLAY 0.489362 (-4540 3855);
FORCEPROP 1 LASTPIN (-4550 3675) $PN 2
J 0
(-4540 3655);
DISPLAY 0.489362 (-4540 3655);
FORCEPROP 1 LAST MATERIAL X6S
J 0
(-4500 3675);
DISPLAY 0.489362 (-4500 3675);
PAINT SKYBLUE (-4500 3675);
FORCEPROP 1 LAST TOLERANCE 20%
J 0
(-4500 3725);
DISPLAY 0.489362 (-4500 3725);
PAINT SKYBLUE (-4500 3725);
FORCEPROP 1 LAST VALUE 22UF
J 0
(-4500 3825);
DISPLAY 0.489362 (-4500 3825);
PAINT SKYBLUE (-4500 3825);
FORCEPROP 1 LAST PART_NUMBER CH622KMEB02
J 0
(-4500 3625);
DISPLAY 0.489362 (-4500 3625);
PAINT SKYBLUE (-4500 3625);
FORCEPROP 1 LAST VOLTAGE 4V
J 0
(-4500 3775);
DISPLAY 0.489362 (-4500 3775);
PAINT SKYBLUE (-4500 3775);
FORCEPROP 1 LAST PACK_TYPE C0402
J 0
(-4500 3575);
DISPLAY 0.489362 (-4500 3575);
PAINT SKYBLUE (-4500 3575);
FORCEPROP 2 LAST CDS_LIB pure_quanta
J 0
(-4550 3775);
PAINT MONO (-4550 3775);
DISPLAY INVISIBLE (-4550 3775);
FORCEPROP 1 LAST PATH I18
J 0
(-4500 3925);
DISPLAY 0.978723 (-4500 3925);
PAINT WHITE (-4500 3925);
DISPLAY INVISIBLE (-4500 3925);
FORCEADD UNIVERSAL_GND..1
(-8100 5025);
FORCEPROP 3 LASTPIN (-8100 5075) SIG_NAME GND\g
J 0
(-8090 5085);
DISPLAY 0.659574 (-8090 5085);
PAINT MONO (-8090 5085);
DISPLAY INVISIBLE (-8090 5085);
FORCEPROP 2 LAST CDS_LIB pure_quanta_power
J 0
(-8100 5025);
PAINT MONO (-8100 5025);
DISPLAY INVISIBLE (-8100 5025);
FORCEPROP 1 LAST PATH I19
J 0
(-8025 5025);
DISPLAY 0.872340 (-8025 5025);
PAINT AQUA (-8025 5025);
DISPLAY INVISIBLE (-8025 5025);
FORCEPROP 1 LAST HDL_POWER GND
J 1
(-8075 4950);
DISPLAY 0.872340 (-8075 4950);
PAINT GREEN (-8075 4950);
DISPLAY INVISIBLE (-8075 4950);
FORCEADD UNIVERSAL_POWER..1
(-8550 3275);
FORCEPROP 3 LASTPIN (-8550 3225) SIG_NAME PVDD18_S5_P1\g
J 0
(-8540 3235);
DISPLAY 0.659574 (-8540 3235);
PAINT MONO (-8540 3235);
DISPLAY INVISIBLE (-8540 3235);
FORCEPROP 1 LAST HDL_POWER PVDD18_S5_P1
J 1
(-8550 3325);
DISPLAY 0.489362 (-8550 3325);
PAINT GREEN (-8550 3325);
FORCEPROP 2 LAST CDS_LIB pure_quanta_power
J 0
(-8550 3275);
DISPLAY INVISIBLE (-8550 3275);
FORCEPROP 1 LAST PATH I2
J 0
(-8500 3300);
DISPLAY 0.872340 (-8500 3300);
PAINT AQUA (-8500 3300);
DISPLAY INVISIBLE (-8500 3300);
FORCEADD Q_CAP..1
(-8100 5400);
FORCEPROP 1 LAST LOCATION C2662
J 0
(-8050 5500);
DISPLAY 0.489362 (-8050 5500);
PAINT SKYBLUE (-8050 5500);
FORCEPROP 2 LAST $SEC 1
J 0
(-8050 5600);
DISPLAY 0.680851 (-8050 5600);
PAINT MONO (-8050 5600);
DISPLAY INVISIBLE (-8050 5600);
FORCEPROP 2 LAST CDS_SEC 1
J 0
(-8050 5600);
DISPLAY 1.021277 (-8050 5600);
DISPLAY INVISIBLE (-8050 5600);
FORCEPROP 1 LASTPIN (-8100 5500) $PN 1
J 0
(-8090 5480);
DISPLAY 0.489362 (-8090 5480);
FORCEPROP 1 LASTPIN (-8100 5300) $PN 2
J 0
(-8090 5280);
DISPLAY 0.489362 (-8090 5280);
FORCEPROP 1 LAST MATERIAL X6S
J 0
(-8050 5300);
DISPLAY 0.489362 (-8050 5300);
PAINT SKYBLUE (-8050 5300);
FORCEPROP 1 LAST TOLERANCE 20%
J 0
(-8050 5350);
DISPLAY 0.489362 (-8050 5350);
PAINT SKYBLUE (-8050 5350);
FORCEPROP 1 LAST VALUE 22UF
J 0
(-8050 5450);
DISPLAY 0.489362 (-8050 5450);
PAINT SKYBLUE (-8050 5450);
FORCEPROP 1 LAST PART_NUMBER CH622KMEB02
J 0
(-8050 5250);
DISPLAY 0.489362 (-8050 5250);
PAINT SKYBLUE (-8050 5250);
FORCEPROP 1 LAST VOLTAGE 4V
J 0
(-8050 5400);
DISPLAY 0.489362 (-8050 5400);
PAINT SKYBLUE (-8050 5400);
FORCEPROP 1 LAST PACK_TYPE C0402
J 0
(-8050 5200);
DISPLAY 0.489362 (-8050 5200);
PAINT SKYBLUE (-8050 5200);
FORCEPROP 2 LAST CDS_LIB pure_quanta
J 0
(-8100 5400);
PAINT MONO (-8100 5400);
DISPLAY INVISIBLE (-8100 5400);
FORCEPROP 1 LAST PATH I20
J 0
(-8050 5550);
DISPLAY 0.978723 (-8050 5550);
PAINT WHITE (-8050 5550);
DISPLAY INVISIBLE (-8050 5550);
FORCEADD Q_CAP..1
(-8550 3775);
FORCEPROP 1 LAST LOCATION C2660
J 0
(-8500 3875);
DISPLAY 0.489362 (-8500 3875);
PAINT SKYBLUE (-8500 3875);
FORCEPROP 2 LAST $SEC 1
J 0
(-8500 3975);
DISPLAY 0.680851 (-8500 3975);
PAINT MONO (-8500 3975);
DISPLAY INVISIBLE (-8500 3975);
FORCEPROP 2 LAST CDS_SEC 1
J 0
(-8500 3975);
DISPLAY 1.021277 (-8500 3975);
DISPLAY INVISIBLE (-8500 3975);
FORCEPROP 1 LASTPIN (-8550 3875) $PN 1
J 0
(-8540 3855);
DISPLAY 0.489362 (-8540 3855);
FORCEPROP 1 LASTPIN (-8550 3675) $PN 2
J 0
(-8540 3655);
DISPLAY 0.489362 (-8540 3655);
FORCEPROP 1 LAST MATERIAL X6S
J 0
(-8500 3675);
DISPLAY 0.489362 (-8500 3675);
PAINT SKYBLUE (-8500 3675);
FORCEPROP 1 LAST TOLERANCE 20%
J 0
(-8500 3725);
DISPLAY 0.489362 (-8500 3725);
PAINT SKYBLUE (-8500 3725);
FORCEPROP 1 LAST VALUE 22UF
J 0
(-8500 3825);
DISPLAY 0.489362 (-8500 3825);
PAINT SKYBLUE (-8500 3825);
FORCEPROP 1 LAST PART_NUMBER CH622KMEB02
J 0
(-8500 3625);
DISPLAY 0.489362 (-8500 3625);
PAINT SKYBLUE (-8500 3625);
FORCEPROP 1 LAST VOLTAGE 4V
J 0
(-8500 3775);
DISPLAY 0.489362 (-8500 3775);
PAINT SKYBLUE (-8500 3775);
FORCEPROP 1 LAST PACK_TYPE C0402
J 0
(-8500 3575);
DISPLAY 0.489362 (-8500 3575);
PAINT SKYBLUE (-8500 3575);
FORCEPROP 2 LAST CDS_LIB pure_quanta
J 0
(-8550 3775);
PAINT MONO (-8550 3775);
DISPLAY INVISIBLE (-8550 3775);
FORCEPROP 1 LAST PATH I3
J 0
(-8500 3925);
DISPLAY 0.978723 (-8500 3925);
PAINT WHITE (-8500 3925);
DISPLAY INVISIBLE (-8500 3925);
FORCEADD UNIVERSAL_POWER..1
(-8550 4050);
FORCEPROP 3 LASTPIN (-8550 4000) SIG_NAME PVDD18_S5_P1\g
J 0
(-8540 4010);
DISPLAY 0.659574 (-8540 4010);
PAINT MONO (-8540 4010);
DISPLAY INVISIBLE (-8540 4010);
FORCEPROP 1 LAST HDL_POWER PVDD18_S5_P1
J 1
(-8550 4100);
DISPLAY 0.489362 (-8550 4100);
PAINT GREEN (-8550 4100);
FORCEPROP 2 LAST CDS_LIB pure_quanta_power
J 0
(-8550 4050);
DISPLAY INVISIBLE (-8550 4050);
FORCEPROP 1 LAST PATH I4
J 0
(-8500 4075);
DISPLAY 0.872340 (-8500 4075);
PAINT AQUA (-8500 4075);
DISPLAY INVISIBLE (-8500 4075);
FORCEADD Q_CAP..1
(-8550 5400);
FORCEPROP 1 LAST LOCATION C2659
J 0
(-8500 5500);
DISPLAY 0.489362 (-8500 5500);
PAINT SKYBLUE (-8500 5500);
FORCEPROP 2 LAST $SEC 1
J 0
(-8500 5600);
DISPLAY 0.680851 (-8500 5600);
PAINT MONO (-8500 5600);
DISPLAY INVISIBLE (-8500 5600);
FORCEPROP 2 LAST CDS_SEC 1
J 0
(-8500 5600);
DISPLAY 1.021277 (-8500 5600);
DISPLAY INVISIBLE (-8500 5600);
FORCEPROP 1 LASTPIN (-8550 5500) $PN 1
J 0
(-8540 5480);
DISPLAY 0.489362 (-8540 5480);
FORCEPROP 1 LASTPIN (-8550 5300) $PN 2
J 0
(-8540 5280);
DISPLAY 0.489362 (-8540 5280);
FORCEPROP 1 LAST MATERIAL X6S
J 0
(-8500 5300);
DISPLAY 0.489362 (-8500 5300);
PAINT SKYBLUE (-8500 5300);
FORCEPROP 1 LAST TOLERANCE 20%
J 0
(-8500 5350);
DISPLAY 0.489362 (-8500 5350);
PAINT SKYBLUE (-8500 5350);
FORCEPROP 1 LAST VALUE 22UF
J 0
(-8500 5450);
DISPLAY 0.489362 (-8500 5450);
PAINT SKYBLUE (-8500 5450);
FORCEPROP 1 LAST PART_NUMBER CH622KMEB02
J 0
(-8500 5250);
DISPLAY 0.489362 (-8500 5250);
PAINT SKYBLUE (-8500 5250);
FORCEPROP 1 LAST VOLTAGE 4V
J 0
(-8500 5400);
DISPLAY 0.489362 (-8500 5400);
PAINT SKYBLUE (-8500 5400);
FORCEPROP 1 LAST PACK_TYPE C0402
J 0
(-8500 5200);
DISPLAY 0.489362 (-8500 5200);
PAINT SKYBLUE (-8500 5200);
FORCEPROP 2 LAST CDS_LIB pure_quanta
J 0
(-8550 5400);
PAINT MONO (-8550 5400);
DISPLAY INVISIBLE (-8550 5400);
FORCEPROP 1 LAST PATH I5
J 0
(-8500 5550);
DISPLAY 0.978723 (-8500 5550);
PAINT WHITE (-8500 5550);
DISPLAY INVISIBLE (-8500 5550);
FORCEADD UNIVERSAL_POWER..1
(-8550 5675);
FORCEPROP 3 LASTPIN (-8550 5625) SIG_NAME PVDD_33_S5\g
J 0
(-8540 5635);
DISPLAY 0.659574 (-8540 5635);
PAINT MONO (-8540 5635);
DISPLAY INVISIBLE (-8540 5635);
FORCEPROP 1 LAST HDL_POWER PVDD_33_S5
J 1
(-8550 5725);
DISPLAY 0.489362 (-8550 5725);
PAINT GREEN (-8550 5725);
FORCEPROP 2 LAST CDS_LIB pure_quanta_power
J 0
(-8550 5675);
DISPLAY INVISIBLE (-8550 5675);
FORCEPROP 1 LAST PATH I6
J 0
(-8500 5700);
DISPLAY 0.872340 (-8500 5700);
PAINT AQUA (-8500 5700);
DISPLAY INVISIBLE (-8500 5700);
FORCEADD UNIVERSAL_GND..1
(-8100 2625);
FORCEPROP 3 LASTPIN (-8100 2675) SIG_NAME GND\g
J 0
(-8090 2685);
DISPLAY 0.659574 (-8090 2685);
PAINT MONO (-8090 2685);
DISPLAY INVISIBLE (-8090 2685);
FORCEPROP 2 LAST CDS_LIB pure_quanta_power
J 0
(-8100 2625);
DISPLAY INVISIBLE (-8100 2625);
FORCEPROP 1 LAST PATH I7
J 0
(-8025 2625);
DISPLAY 0.872340 (-8025 2625);
PAINT AQUA (-8025 2625);
DISPLAY INVISIBLE (-8025 2625);
FORCEPROP 1 LAST HDL_POWER GND
J 1
(-8075 2550);
DISPLAY 0.872340 (-8075 2550);
PAINT GREEN (-8075 2550);
DISPLAY INVISIBLE (-8075 2550);
FORCEADD Q_CAP..1
(-8100 3000);
FORCEPROP 1 LAST LOCATION C2664
J 0
(-8050 3100);
DISPLAY 0.489362 (-8050 3100);
PAINT SKYBLUE (-8050 3100);
FORCEPROP 2 LAST $SEC 1
J 0
(-8050 3200);
DISPLAY 0.680851 (-8050 3200);
PAINT MONO (-8050 3200);
DISPLAY INVISIBLE (-8050 3200);
FORCEPROP 2 LAST CDS_SEC 1
J 0
(-8050 3200);
DISPLAY 1.021277 (-8050 3200);
DISPLAY INVISIBLE (-8050 3200);
FORCEPROP 1 LASTPIN (-8100 3100) $PN 1
J 0
(-8090 3080);
DISPLAY 0.489362 (-8090 3080);
FORCEPROP 1 LASTPIN (-8100 2900) $PN 2
J 0
(-8090 2880);
DISPLAY 0.489362 (-8090 2880);
FORCEPROP 1 LAST MATERIAL X6S
J 0
(-8050 2900);
DISPLAY 0.489362 (-8050 2900);
PAINT SKYBLUE (-8050 2900);
FORCEPROP 1 LAST TOLERANCE 20%
J 0
(-8050 2950);
DISPLAY 0.489362 (-8050 2950);
PAINT SKYBLUE (-8050 2950);
FORCEPROP 1 LAST VALUE 22UF
J 0
(-8050 3050);
DISPLAY 0.489362 (-8050 3050);
PAINT SKYBLUE (-8050 3050);
FORCEPROP 1 LAST PART_NUMBER CH622KMEB02
J 0
(-8050 2850);
DISPLAY 0.489362 (-8050 2850);
PAINT SKYBLUE (-8050 2850);
FORCEPROP 1 LAST VOLTAGE 4V
J 0
(-8050 3000);
DISPLAY 0.489362 (-8050 3000);
PAINT SKYBLUE (-8050 3000);
FORCEPROP 1 LAST PACK_TYPE C0402
J 0
(-8050 2800);
DISPLAY 0.489362 (-8050 2800);
PAINT SKYBLUE (-8050 2800);
FORCEPROP 2 LAST CDS_LIB pure_quanta
J 0
(-8100 3000);
PAINT MONO (-8100 3000);
DISPLAY INVISIBLE (-8100 3000);
FORCEPROP 1 LAST PATH I8
J 0
(-8050 3150);
DISPLAY 0.978723 (-8050 3150);
PAINT WHITE (-8050 3150);
DISPLAY INVISIBLE (-8050 3150);
FORCEADD Q_CAP..1
(-8100 3775);
FORCEPROP 1 LAST LOCATION C2663
J 0
(-8050 3875);
DISPLAY 0.489362 (-8050 3875);
PAINT SKYBLUE (-8050 3875);
FORCEPROP 2 LAST $SEC 1
J 0
(-8050 3975);
DISPLAY 0.680851 (-8050 3975);
PAINT MONO (-8050 3975);
DISPLAY INVISIBLE (-8050 3975);
FORCEPROP 2 LAST CDS_SEC 1
J 0
(-8050 3975);
DISPLAY 1.021277 (-8050 3975);
DISPLAY INVISIBLE (-8050 3975);
FORCEPROP 1 LASTPIN (-8100 3875) $PN 1
J 0
(-8090 3855);
DISPLAY 0.489362 (-8090 3855);
FORCEPROP 1 LASTPIN (-8100 3675) $PN 2
J 0
(-8090 3655);
DISPLAY 0.489362 (-8090 3655);
FORCEPROP 1 LAST MATERIAL X6S
J 0
(-8050 3675);
DISPLAY 0.489362 (-8050 3675);
PAINT SKYBLUE (-8050 3675);
FORCEPROP 1 LAST TOLERANCE 20%
J 0
(-8050 3725);
DISPLAY 0.489362 (-8050 3725);
PAINT SKYBLUE (-8050 3725);
FORCEPROP 1 LAST VALUE 22UF
J 0
(-8050 3825);
DISPLAY 0.489362 (-8050 3825);
PAINT SKYBLUE (-8050 3825);
FORCEPROP 1 LAST PART_NUMBER CH622KMEB02
J 0
(-8050 3625);
DISPLAY 0.489362 (-8050 3625);
PAINT SKYBLUE (-8050 3625);
FORCEPROP 1 LAST VOLTAGE 4V
J 0
(-8050 3775);
DISPLAY 0.489362 (-8050 3775);
PAINT SKYBLUE (-8050 3775);
FORCEPROP 1 LAST PACK_TYPE C0402
J 0
(-8050 3575);
DISPLAY 0.489362 (-8050 3575);
PAINT SKYBLUE (-8050 3575);
FORCEPROP 2 LAST CDS_LIB pure_quanta
J 0
(-8100 3775);
PAINT MONO (-8100 3775);
DISPLAY INVISIBLE (-8100 3775);
FORCEPROP 1 LAST PATH I9
J 0
(-8050 3925);
DISPLAY 0.978723 (-8050 3925);
PAINT WHITE (-8050 3925);
DISPLAY INVISIBLE (-8050 3925);
FORCEADD QUANTA_TITLE_BLOCK_C..1
(0 0);
FORCEPROP 0 LAST CDS_CON_LAST_MODIFIED Fri Mar 11 14:52:47 2022
J 0
(-1885 15);
DISPLAY INVISIBLE (-1885 15);
FORCEPROP 1 LAST CUSTOM_TXT_CDS <CON_LAST_MODIFIED>
J 0
(-1885 15);
DISPLAY 0.978723 (-1885 15);
FORCEPROP 2 LAST CUSTOM_TXT_CDS <XR_PAGE_TITLE>
J 0
(-7890 5250);
DISPLAY 0.638298 (-7890 5250);
PAINT PINK (-7890 5250);
DISPLAY INVISIBLE (-7890 5250);
FORCEPROP 1 LAST CUSTOM_TXT_CDS <NAME_2>
J 0
(-3175 50);
FORCEPROP 1 LAST CUSTOM_TXT_CDS <NAME_1>
J 0
(-3175 175);
FORCEPROP 1 LAST CUSTOM_TXT_CDS <Q_NUMBER>
J 0
(-1403 103);
DISPLAY 1.212766 (-1403 103);
FORCEPROP 1 LAST CUSTOM_TXT_CDS <Q_PROJ>
J 0
(-2382 102);
DISPLAY 1.212766 (-2382 102);
FORCEPROP 1 LAST CUSTOM_TXT_CDS <Q_REV>
J 0
(-184 103);
DISPLAY 1.212766 (-184 103);
FORCEPROP 1 LAST CUSTOM_TXT_CDS <CON_PAGE_NUM> OF <CON_TOTAL_PAGES>
J 0
(-446 18);
DISPLAY 0.978723 (-446 18);
FORCEPROP 1 LAST Q_TITLE CPU1 CAVITY BOT DECOUPLING CAPS 3/3
J 0
(-9366 26);
DISPLAY 2.446809 (-9366 26);
PAINT GREEN (-9366 26);
FORCEPROP 1 LAST Q_DEPT BU9
J 1
(-3763 49);
DISPLAY 1.957447 (-3763 49);
PAINT GREEN (-3763 49);
FORCEPROP 2 LAST PAGE_BORDER TRUE
J 0
(-7890 5250);
DISPLAY 0.638298 (-7890 5250);
PAINT PINK (-7890 5250);
DISPLAY INVISIBLE (-7890 5250);
FORCEPROP 1 LAST CDS_LMAN_SYM_OUTLINE -9475,6775,100,-125
J 0
(0 0);
DISPLAY 0.468085 (0 0);
PAINT GREEN (0 0);
DISPLAY INVISIBLE (0 0);
FORCEPROP 2 LAST CDS_LIB pure_quanta
J 0
(0 0);
DISPLAY INVISIBLE (0 0);
FORCEPROP 1 LAST COMMENT_BODY TRUE
J 0
(12 -13);
DISPLAY 0.978723 (12 -13);
PAINT GREEN (12 -13);
DISPLAY INVISIBLE (12 -13);
FORCEPROP 2 LAST CDS_XR_PAGE_TITLE CR-74 : @T6G_MB_LIB.T6G(SCH_1):PAGE74
J 0
(-7890 5250);
DISPLAY 0.638298 (-7890 5250);
PAINT PINK (-7890 5250);
DISPLAY INVISIBLE (-7890 5250);
WIRE 16 3135 (-8775 4900)(-4850 4900);
WIRE 16 3135 (-8775 4900)(-8775 6175);
WIRE 16 3135 (-4850 4900)(-4850 6175);
WIRE 16 3135 (-8775 6175)(-4850 6175);
WIRE 16 3135 (-8775 2475)(-4025 2475);
WIRE 16 3135 (-8775 2475)(-8775 4600);
WIRE 16 3135 (-4025 2475)(-4025 4600);
WIRE 16 3135 (-8775 4600)(-4025 4600);
WIRE 16 -1 (-8100 3550)(-8550 3550);
WIRE 16 -1 (-7650 3550)(-8100 3550);
WIRE 16 -1 (-8100 3550)(-8100 3675);
WIRE 16 -1 (-8550 3550)(-8550 3675);
WIRE 16 -1 (-7650 3550)(-7650 3675);
WIRE 16 -1 (-7200 3550)(-7650 3550);
WIRE 16 -1 (-6750 3550)(-7200 3550);
WIRE 16 -1 (-7200 3550)(-7200 3675);
WIRE 16 -1 (-6300 3550)(-6750 3550);
WIRE 16 -1 (-6750 3550)(-6750 3675);
WIRE 16 -1 (-5850 3550)(-6300 3550);
WIRE 16 -1 (-6300 3550)(-6300 3675);
WIRE 16 -1 (-5400 3550)(-5850 3550);
WIRE 16 -1 (-5850 3550)(-5850 3675);
WIRE 16 -1 (-4950 3550)(-5400 3550);
WIRE 16 -1 (-5400 3550)(-5400 3675);
WIRE 16 -1 (-4550 3550)(-4950 3550);
WIRE 16 -1 (-4950 3550)(-4950 3675);
WIRE 16 -1 (-4550 3550)(-4550 3675);
WIRE 16 -1 (-4550 3450)(-4550 3550);
WIRE 16 -1 (-8100 5175)(-8550 5175);
WIRE 16 -1 (-8100 5175)(-8100 5300);
WIRE 16 -1 (-8100 5075)(-8100 5175);
WIRE 16 -1 (-8550 5175)(-8550 5300);
WIRE 16 -1 (-8100 3175)(-8550 3175);
WIRE 16 -1 (-8100 3100)(-8100 3175);
WIRE 16 -1 (-8550 3175)(-8550 3225);
WIRE 16 -1 (-8550 3175)(-8550 3100);
WIRE 16 -1 (-4550 3875)(-4550 3950);
WIRE 16 -1 (-4550 3950)(-4950 3950);
WIRE 16 -1 (-4950 3950)(-4950 3875);
WIRE 16 -1 (-4950 3950)(-5400 3950);
WIRE 16 -1 (-5400 3875)(-5400 3950);
WIRE 16 -1 (-5400 3950)(-5850 3950);
WIRE 16 -1 (-5850 3875)(-5850 3950);
WIRE 16 -1 (-5850 3950)(-6300 3950);
WIRE 16 -1 (-6300 3950)(-6300 3875);
WIRE 16 -1 (-6300 3950)(-6750 3950);
WIRE 16 -1 (-6750 3875)(-6750 3950);
WIRE 16 -1 (-6750 3950)(-7200 3950);
WIRE 16 -1 (-7200 3875)(-7200 3950);
WIRE 16 -1 (-7200 3950)(-7650 3950);
WIRE 16 -1 (-7650 3950)(-7650 3875);
WIRE 16 -1 (-7650 3950)(-8100 3950);
WIRE 16 -1 (-8100 3950)(-8550 3950);
WIRE 16 -1 (-8100 3875)(-8100 3950);
WIRE 16 -1 (-8550 3950)(-8550 4000);
WIRE 16 -1 (-8550 3950)(-8550 3875);
WIRE 16 -1 (-8100 5575)(-8550 5575);
WIRE 16 -1 (-8100 5500)(-8100 5575);
WIRE 16 -1 (-8550 5575)(-8550 5625);
WIRE 16 -1 (-8550 5575)(-8550 5500);
WIRE 16 -1 (-8100 2775)(-8550 2775);
WIRE 16 -1 (-8100 2775)(-8100 2900);
WIRE 16 -1 (-8100 2675)(-8100 2775);
WIRE 16 -1 (-8550 2775)(-8550 2900);
DOT 1 (-8550 3175);
DOT 1 (-8550 3950);
DOT 1 (-8550 5575);
DOT 1 (-8100 2775);
DOT 1 (-8100 3550);
DOT 1 (-8100 3950);
DOT 1 (-7650 3550);
DOT 1 (-7650 3950);
DOT 1 (-6750 3550);
DOT 1 (-7200 3550);
DOT 1 (-7200 3950);
DOT 1 (-6750 3950);
DOT 1 (-6300 3550);
DOT 1 (-6300 3950);
DOT 1 (-5850 3550);
DOT 1 (-5850 3950);
DOT 1 (-5400 3550);
DOT 1 (-4950 3550);
DOT 1 (-4950 3950);
DOT 1 (-4550 3550);
DOT 1 (-8100 5175);
DOT 1 (-5400 3950);
FORCENOTE
PVDD33_S5: 2PCS 22UF ON BOT
(-8575 5900) 0;
DISPLAY LEFT (-8575 5900);
DISPLAY 2.510638 (-8575 5900);
PAINT WHITE (-8575 5900);
FORCENOTE
5
(-6775 4025) 0;
DISPLAY LEFT (-6775 4025);
DISPLAY 1.021277 (-6775 4025);
PAINT SKYBLUE (-6775 4025);
FORCENOTE
10
(-4600 4025) 0;
DISPLAY LEFT (-4600 4025);
DISPLAY 1.021277 (-4600 4025);
PAINT SKYBLUE (-4600 4025);
FORCENOTE
PVDD18_S5_P1: 12PCS 22UF ON BOT
(-8625 4375) 0;
DISPLAY LEFT (-8625 4375);
DISPLAY 2.510638 (-8625 4375);
PAINT WHITE (-8625 4375);
QUIT
